# S9S_MB_2U (Grand Teton) — schematic netlist excerpt (pin names and nets, part order shuffled) for the footprints in the layout excerpt that follows; sources: Cadence DE-HDL packaged netlist, KiCad conversion of 03242023_DA0F0TMBIJ0_F0T_Motherboard_J_brd_V01_OCP.brd

PU30_P1_2  ISL99390FRZTR5935  ISL99390FRZ-TR5935 IC  pkg QFN21_6X5XB  page 285
  VOS  = PVCCIN_CPU1_VOS2
  AGND  = GND
  VCC  = PVCCIN_CPU1_VDD2
  PVCC  = PVCCIN_CPU1_PVCC
  PGND1  = GND
  GL1  = NC
  PGND2  = GND
  SW  = SW_PVCCIN_CPU1_SW2
  VIN1  = SW_P12V_PVCCIN_CPU1_FLT
  VIN2  = SW_P12V_PVCCIN_CPU1_FLT
  DNC  = NC
  PHASE  = SW_PVCCIN_CPU1_BOOTR2
  BOOT  = SW_PVCCIN_CPU1_BOOT2
  PWM  = PVCCIN_CPU1_PWM2
  EN  = PVCCIN_CPU1_VDD2
  TOUT_FLT  = PVCCIN_CPU1_ATSEN
  LSET  = PVCCIN_CPU1_LSET2
  IOUT  = PVCCIN_CPU1_IMON2
  REFIN  = PVCCIN_CPU1_VREF
  PGND3  = GND
  GL2  = NC

(kicad_pcb
	(version 20260206)
	(generator "pcbnew")
	(generator_version "10.0")
	(general
		(thickness 1.6)
		(legacy_teardrops no)
	)
	(paper "A4")
	(title_block
		(title "03242023_DA0F0TMBIJ0_F0T_Motherboard_J_brd_V01_OCP.brd")
		(comment 1 "Grand Teton / footprints 647-647 of 6105")
	)
	(layers
		(0 "F.Cu" signal "TOP")
		(4 "In1.Cu" signal "GND")
		(6 "In2.Cu" signal "IN1")
		(8 "In3.Cu" signal "GND1")
		(10 "In4.Cu" signal "IN2")
		(12 "In5.Cu" signal "GND2")
		(14 "In6.Cu" signal "IN3")
		(16 "In7.Cu" signal "GND3")
		(18 "In8.Cu" signal "VCC")
		(20 "In9.Cu" signal "VCC1")
		(22 "In10.Cu" signal "GND4")
		(24 "In11.Cu" signal "IN4")
		(26 "In12.Cu" signal "GND5")
		(28 "In13.Cu" signal "IN5")
		(30 "In14.Cu" signal "GND6")
		(32 "In15.Cu" signal "IN6")
		(34 "In16.Cu" signal "GND7")
		(2 "B.Cu" signal "BOTTOM")
		(9 "F.Adhes" user "F.Adhesive")
		(11 "B.Adhes" user "B.Adhesive")
		(13 "F.Paste" user "Package Geometry/Pastemask Top")
		(15 "B.Paste" user "Package Geometry/Pastemask Bottom")
		(5 "F.SilkS" user "Ref Des/Silkscreen Top")
		(7 "B.SilkS" user "Ref Des/Silkscreen Bottom")
		(1 "F.Mask" user "Board Geometry/Soldermask Top")
		(3 "B.Mask" user "Board Geometry/Soldermask Bottom")
		(17 "Dwgs.User" user "User.Drawings")
		(19 "Cmts.User" user "User.Comments")
		(21 "Eco1.User" user "User.Eco1")
		(23 "Eco2.User" user "User.Eco2")
		(25 "Edge.Cuts" user "Board Geometry/Outline")
		(27 "Margin" user)
		(31 "F.CrtYd" user "Package Geometry/Place Bound Top")
		(29 "B.CrtYd" user "Package Geometry/Place Bound Bottom")
		(35 "F.Fab" user "Ref Des/Assembly Top")
		(33 "B.Fab" user "Ref Des/Assembly Bottom")
	)
	(footprint ""
		(layer "F.Cu")
		(at 105.158286 -333.716122)
		(property "Reference" "PU30_P1_2"
			(at -2.670048 -6.321298 0)
			(unlocked yes)
			(layer "F.SilkS")
			(effects
				(font
					(size 0.7874 0.5842)
					(thickness 0.1524)
				)
				(justify left)
			)
		)
		(property "Value" ""
			(at 0 0 0)
			(layer "F.Fab")
			(effects
				(font
					(size 1.27 1.27)
				)
			)
		)
		(duplicate_pad_numbers_are_jumpers no)
		(fp_line
			(start -2.500122 -2.999994)
			(end -2.24409 -2.999994)
			(stroke
				(width 0.1524)
				(type default)
			)
			(layer "F.SilkS")
		)
		(fp_line
			(start -2.500122 -2.529078)
			(end -2.500122 -2.999994)
			(stroke
				(width 0.1524)
				(type default)
			)
			(layer "F.SilkS")
		)
		(fp_line
			(start -2.500122 0.6604)
			(end -2.500122 0.229108)
			(stroke
				(width 0.1524)
				(type default)
			)
			(layer "F.SilkS")
		)
		(fp_line
			(start -2.500122 2.999994)
			(end -2.500122 2.339594)
			(stroke
				(width 0.1524)
				(type default)
			)
			(layer "F.SilkS")
		)
		(fp_line
			(start -2.2987 2.999994)
			(end -2.500122 2.999994)
			(stroke
				(width 0.1524)
				(type default)
			)
			(layer "F.SilkS")
		)
		(fp_line
			(start 2.31394 -2.999994)
			(end 2.500122 -2.999994)
			(stroke
				(width 0.1524)
				(type default)
			)
			(layer "F.SilkS")
		)
		(fp_line
			(start 2.500122 -2.999994)
			(end 2.500122 -2.44348)
			(stroke
				(width 0.1524)
				(type default)
			)
			(layer "F.SilkS")
		)
		(fp_line
			(start 2.500122 2.339594)
			(end 2.500122 2.999994)
			(stroke
				(width 0.1524)
				(type default)
			)
			(layer "F.SilkS")
		)
		(fp_line
			(start 2.500122 2.999994)
			(end 2.2987 2.999994)
			(stroke
				(width 0.1524)
				(type default)
			)
			(layer "F.SilkS")
		)
		(fp_poly
			(pts
				(xy -2.156714 -3.626612) (xy -2.664714 -2.610612) (xy -3.172714 -3.626612)
			)
			(stroke
				(width 0)
				(type default)
			)
			(fill yes)
			(layer "F.SilkS")
		)
		(fp_line
			(start -2.500122 -2.999994)
			(end 2.500122 -2.999994)
			(stroke
				(width 0.1)
				(type default)
			)
			(layer "F.Fab")
		)
		(fp_line
			(start -2.500122 2.999994)
			(end -2.500122 -2.999994)
			(stroke
				(width 0.1)
				(type default)
			)
			(layer "F.Fab")
		)
		(fp_line
			(start 2.500122 -2.999994)
			(end 2.500122 2.999994)
			(stroke
				(width 0.1)
				(type default)
			)
			(layer "F.Fab")
		)
		(fp_line
			(start 2.500122 2.999994)
			(end -2.500122 2.999994)
			(stroke
				(width 0.1)
				(type default)
			)
			(layer "F.Fab")
		)
		(fp_poly
			(pts
				(xy -4.218432 -2.783078) (xy -4.218432 -1.767078) (xy -3.202432 -2.275078)
			)
			(stroke
				(width 0)
				(type default)
			)
			(fill yes)
			(layer "F.Fab")
		)
		(pad "1" smd rect
			(at -2.400046 -2.275078 90)
			(size 0.2286 0.6096)
			(layers "F.Cu" "F.Mask" "F.Paste")
			(net "PVCCIN_CPU1_VOS2")
		)
		(pad "2" smd rect
			(at -2.400046 -1.82499 90)
			(size 0.2286 0.6096)
			(layers "F.Cu" "F.Mask" "F.Paste")
			(net "GND")
		)
		(pad "3" smd rect
			(at -2.400046 -1.374902 90)
			(size 0.2286 0.6096)
			(layers "F.Cu" "F.Mask" "F.Paste")
			(net "PVCCIN_CPU1_VDD2")
		)
		(pad "4" smd rect
			(at -2.400046 -0.925068 90)
			(size 0.2286 0.6096)
			(layers "F.Cu" "F.Mask" "F.Paste")
			(net "PVCCIN_CPU1_PVCC")
		)
		(pad "5" smd rect
			(at -2.400046 -0.47498 90)
			(size 0.2286 0.6096)
			(layers "F.Cu" "F.Mask" "F.Paste")
			(net "GND")
		)
		(pad "6" smd rect
			(at -2.400046 -0.024892 90)
			(size 0.2286 0.6096)
			(layers "F.Cu" "F.Mask" "F.Paste")
			(net "Net_8523")
		)
		(pad "7_9-20_24" smd circle
			(at 0 1.150112 90)
			(size 0 0)
			(layers "F.Cu" "F.Mask" "F.Paste")
			(net "GND")
		)
		(pad "10_19" smd rect
			(at 0 2.899918 90)
			(size 0.6096 4.318)
			(layers "F.Cu" "F.Mask" "F.Paste")
			(net "SW_PVCCIN_CPU1_SW2")
		)
		(pad "25_29" smd rect
			(at 1.549908 -1.279906 270)
			(size 2.0574 2.3114)
			(layers "F.Cu" "F.Mask" "F.Paste")
			(net "SW_P12V_PVCCIN_CPU1_FLT")
		)
		(pad "30" smd rect
			(at 2.05994 -2.899918)
			(size 0.2286 0.6096)
			(layers "F.Cu" "F.Mask" "F.Paste")
			(net "SW_P12V_PVCCIN_CPU1_FLT")
		)
		(pad "31" smd rect
			(at 1.610106 -2.899918)
			(size 0.2286 0.6096)
			(layers "F.Cu" "F.Mask" "F.Paste")
			(net "Net_8524")
		)
		(pad "32" smd rect
			(at 1.160018 -2.899918)
			(size 0.2286 0.6096)
			(layers "F.Cu" "F.Mask" "F.Paste")
			(net "SW_PVCCIN_CPU1_BOOTR2")
		)
		(pad "33" smd rect
			(at 0.70993 -2.899918)
			(size 0.2286 0.6096)
			(layers "F.Cu" "F.Mask" "F.Paste")
			(net "SW_PVCCIN_CPU1_BOOT2")
		)
		(pad "34" smd rect
			(at 0.260096 -2.899918)
			(size 0.2286 0.6096)
			(layers "F.Cu" "F.Mask" "F.Paste")
			(net "PVCCIN_CPU1_PWM2")
		)
		(pad "35" smd rect
			(at -0.189992 -2.899918)
			(size 0.2286 0.6096)
			(layers "F.Cu" "F.Mask" "F.Paste")
			(net "PVCCIN_CPU1_VDD2")
		)
		(pad "36" smd rect
			(at -0.64008 -2.899918)
			(size 0.2286 0.6096)
			(layers "F.Cu" "F.Mask" "F.Paste")
			(net "PVCCIN_CPU1_ATSEN")
		)
		(pad "37" smd rect
			(at -1.089914 -2.899918)
			(size 0.2286 0.6096)
			(layers "F.Cu" "F.Mask" "F.Paste")
			(net "PVCCIN_CPU1_LSET2")
		)
		(pad "38" smd rect
			(at -1.540002 -2.899918)
			(size 0.2286 0.6096)
			(layers "F.Cu" "F.Mask" "F.Paste")
			(net "PVCCIN_CPU1_IMON2")
		)
		(pad "39" smd rect
			(at -1.99009 -2.899918)
			(size 0.2286 0.6096)
			(layers "F.Cu" "F.Mask" "F.Paste")
			(net "PVCCIN_CPU1_VREF")
		)
		(pad "40" smd rect
			(at -0.87503 -1.27508)
			(size 1.7526 1.9558)
			(layers "F.Cu" "F.Mask" "F.Paste")
			(net "GND")
		)
		(pad "41" smd rect
			(at -1.525016 0.249936 270)
			(size 0.3048 0.4572)
			(layers "F.Cu" "F.Mask" "F.Paste")
			(net "Net_8522")
		)
		(zone
			(layer "F.Cu")
			(hatch none 0.5)
			(connect_pads
				(clearance 0)
			)
			(min_thickness 0.25)
			(keepout
				(tracks not_allowed)
				(vias allowed)
				(pads allowed)
				(copperpour not_allowed)
				(footprints allowed)
			)
			(placement
				(enabled no)
				(sheetname "")
			)
			(fill
				(thermal_gap 0.5)
				(thermal_bridge_width 0.5)
				(island_removal_mode 0)
			)
			(polygon
				(pts
					(xy 102.658164 -330.716128) (xy 102.658164 -331.465428) (xy 107.658408 -331.465428) (xy 107.658408 -330.716128)
					(xy 107.368086 -330.716128) (xy 107.368086 -331.171804) (xy 102.948486 -331.171804) (xy 102.948486 -330.716128)
				)
			)
		)
		(zone
			(layer "F.Cu")
			(hatch none 0.5)
			(connect_pads
				(clearance 0)
			)
			(min_thickness 0.25)
			(keepout
				(tracks not_allowed)
				(vias allowed)
				(pads allowed)
				(copperpour not_allowed)
				(footprints allowed)
			)
			(placement
				(enabled no)
				(sheetname "")
			)
			(fill
				(thermal_gap 0.5)
				(thermal_bridge_width 0.5)
				(island_removal_mode 0)
			)
			(polygon
				(pts
					(xy 103.11384 -334.040988) (xy 103.356156 -334.040988) (xy 103.356156 -333.962502) (xy 104.13238 -333.962502)
					(xy 104.13238 -333.632048) (xy 104.207564 -333.632048) (xy 104.207564 -332.966822) (xy 102.658164 -332.966822)
					(xy 102.658164 -333.423514) (xy 103.35387 -333.423514) (xy 103.35387 -333.262986) (xy 103.91267 -333.262986)
					(xy 103.91267 -333.669386) (xy 103.35387 -333.669386) (xy 103.35387 -333.448914) (xy 102.658164 -333.448914)
					(xy 102.658164 -333.575914) (xy 103.11384 -333.575914)
				)
			)
		)
	)
)
